(kicad_pcb
	(version 20260206)
	(generator "pcbnew")
	(generator_version "10.0")
	(general
		(thickness 1.6)
		(legacy_teardrops no)
	)
	(paper "A4")
	(title_block
		(title "netronome-mezz — pcbd0082-001_rev01_jul9_a.brd")
		(comment 1 "Open CloudServer (Microsoft) / footprint 702 of 714 (J4), pads 117-162 of 162")
	)
	(layers
		(0 "F.Cu" signal "TOP")
		(4 "In1.Cu" signal "02_GND")
		(6 "In2.Cu" signal "03_SIG")
		(8 "In3.Cu" signal "04_SIG")
		(10 "In4.Cu" signal "05_GND")
		(12 "In5.Cu" signal "06_PWR1")
		(14 "In6.Cu" signal "07_SIG")
		(16 "In7.Cu" signal "08_SIG")
		(18 "In8.Cu" signal "09_GND")
		(2 "B.Cu" signal "BOTTOM")
		(9 "F.Adhes" user "F.Adhesive")
		(11 "B.Adhes" user "B.Adhesive")
		(13 "F.Paste" user "Package Geometry/Pastemask Top")
		(15 "B.Paste" user "Package Geometry/Pastemask Bottom")
		(5 "F.SilkS" user "Ref Des/Silkscreen Top")
		(7 "B.SilkS" user "Ref Des/Silkscreen Bottom")
		(1 "F.Mask" user "Board Geometry/Soldermask Top")
		(3 "B.Mask" user "Board Geometry/Soldermask Bottom")
		(17 "Dwgs.User" user "User.Drawings")
		(19 "Cmts.User" user "User.Comments")
		(21 "Eco1.User" user "User.Eco1")
		(23 "Eco2.User" user "User.Eco2")
		(25 "Edge.Cuts" user "Board Geometry/Outline")
		(27 "Margin" user)
		(31 "F.CrtYd" user "Package Geometry/Place Bound Top")
		(29 "B.CrtYd" user "Package Geometry/Place Bound Bottom")
		(35 "F.Fab" user "Ref Des/Assembly Top")
		(33 "B.Fab" user "Ref Des/Assembly Bottom")
		(45 "User.4" user "COMPVAL_TYPE_BOTTOM")
	)
	(footprint ""
		(layer "B.Cu")
		(at 12.8524 15.8369 -90)
		(property "Reference" "J4"
			(at -15.81023 -6.1976 0)
			(unlocked yes)
			(layer "B.SilkS")
			(effects
				(font
					(size 0.7874 0.5842)
					(thickness 0.127)
				)
				(justify left mirror)
			)
		)
		(property "Value" "VAL"
			(at -0.181864 1.64592 270)
			(unlocked yes)
			(layer "B.Fab")
			(hide yes)
			(effects
				(font
					(size 1.27 0.9652)
					(thickness 0.1524)
				)
				(justify mirror)
			)
		)
		(property "User Part Number" "PN"
			(at -0.181864 -4.06908 270)
			(unlocked yes)
			(layer "Cmts.User")
			(hide yes)
			(effects
				(font
					(size 1.27 0.9652)
					(thickness 0.1524)
				)
				(justify mirror)
			)
		)
		(property "Device Type" "CONM0071"
			(at -0.181864 -2.16408 270)
			(unlocked yes)
			(layer "B.Fab")
			(hide yes)
			(effects
				(font
					(size 1.27 0.9652)
					(thickness 0.1524)
				)
				(justify mirror)
			)
		)
		(property "Tolerance" "TOL"
			(at -0.181864 3.55092 270)
			(unlocked yes)
			(layer "Cmts.User")
			(hide yes)
			(effects
				(font
					(size 1.27 0.9652)
					(thickness 0.1524)
				)
				(justify mirror)
			)
		)
		(duplicate_pad_numbers_are_jumpers no)
		(pad "115" smd circle
			(at 5.715 -1.905 90)
			(size 0.635 0.635)
			(layers "B.Cu" "B.Mask" "B.Paste")
			(net "NFP_PCIE0_PER2_N")
		)
		(pad "116" smd circle
			(at 5.715 -0.635 90)
			(size 0.635 0.635)
			(layers "B.Cu" "B.Mask" "B.Paste")
			(net "GND")
		)
		(pad "117" smd circle
			(at 5.715 0.635 90)
			(size 0.635 0.635)
			(layers "B.Cu" "B.Mask" "B.Paste")
			(net "NWK1_LED_LINK_G_L")
		)
		(pad "118" smd circle
			(at 5.715 1.905 90)
			(size 0.635 0.635)
			(layers "B.Cu" "B.Mask" "B.Paste")
			(net "GND")
		)
		(pad "119" smd circle
			(at 5.715 3.175 90)
			(size 0.635 0.635)
			(layers "B.Cu" "B.Mask" "B.Paste")
			(net "NFP_SERDES1_RX1_P")
		)
		(pad "120" smd circle
			(at 5.715 4.445 90)
			(size 0.635 0.635)
			(layers "B.Cu" "B.Mask" "B.Paste")
			(net "GND")
		)
		(pad "121" smd circle
			(at 6.985 -4.445 90)
			(size 0.635 0.635)
			(layers "B.Cu" "B.Mask" "B.Paste")
			(net "GND")
		)
		(pad "122" smd circle
			(at 6.985 -3.175 90)
			(size 0.635 0.635)
			(layers "B.Cu" "B.Mask" "B.Paste")
			(net "NFP_PCIE0_PET7_P")
		)
		(pad "123" smd circle
			(at 6.985 -1.905 90)
			(size 0.635 0.635)
			(layers "B.Cu" "B.Mask" "B.Paste")
			(net "GND")
		)
		(pad "124" smd circle
			(at 6.985 -0.635 90)
			(size 0.635 0.635)
			(layers "B.Cu" "B.Mask" "B.Paste")
			(net "NFP_PCIE0_PER3_P")
		)
		(pad "125" smd circle
			(at 6.985 0.635 90)
			(size 0.635 0.635)
			(layers "B.Cu" "B.Mask" "B.Paste")
			(net "GND")
		)
		(pad "126" smd circle
			(at 6.985 1.905 90)
			(size 0.635 0.635)
			(layers "B.Cu" "B.Mask" "B.Paste")
			(net "NFP_SERDES0_TX0_P")
		)
		(pad "127" smd circle
			(at 6.985 3.175 90)
			(size 0.635 0.635)
			(layers "B.Cu" "B.Mask" "B.Paste")
			(net "GND")
		)
		(pad "128" smd circle
			(at 6.985 4.445 90)
			(size 0.635 0.635)
			(layers "B.Cu" "B.Mask" "B.Paste")
			(net "NFP_SERDES1_RX2_N")
		)
		(pad "129" smd circle
			(at 8.255 -4.445 90)
			(size 0.635 0.635)
			(layers "B.Cu" "B.Mask" "B.Paste")
			(net "NWK1_I2C_SDA")
		)
		(pad "130" smd circle
			(at 8.255 -3.175 90)
			(size 0.635 0.635)
			(layers "B.Cu" "B.Mask" "B.Paste")
			(net "NFP_PCIE0_PET7_N")
		)
		(pad "131" smd circle
			(at 8.255 -1.905 90)
			(size 0.635 0.635)
			(layers "B.Cu" "B.Mask" "B.Paste")
			(net "GND")
		)
		(pad "132" smd circle
			(at 8.255 -0.635 90)
			(size 0.635 0.635)
			(layers "B.Cu" "B.Mask" "B.Paste")
			(net "NFP_PCIE0_PER3_N")
		)
		(pad "133" smd circle
			(at 8.255 0.635 90)
			(size 0.635 0.635)
			(layers "B.Cu" "B.Mask" "B.Paste")
			(net "GND")
		)
		(pad "134" smd circle
			(at 8.255 1.905 90)
			(size 0.635 0.635)
			(layers "B.Cu" "B.Mask" "B.Paste")
			(net "NFP_SERDES0_TX0_N")
		)
		(pad "135" smd circle
			(at 8.255 3.175 90)
			(size 0.635 0.635)
			(layers "B.Cu" "B.Mask" "B.Paste")
			(net "GND")
		)
		(pad "136" smd circle
			(at 8.255 4.445 90)
			(size 0.635 0.635)
			(layers "B.Cu" "B.Mask" "B.Paste")
			(net "NFP_SERDES1_RX2_P")
		)
		(pad "137" smd circle
			(at 9.525 -4.445 90)
			(size 0.635 0.635)
			(layers "B.Cu" "B.Mask" "B.Paste")
			(net "NWK1_I2C_SCL")
		)
		(pad "138" smd circle
			(at 9.525 -3.175 90)
			(size 0.635 0.635)
			(layers "B.Cu" "B.Mask" "B.Paste")
			(net "GND")
		)
		(pad "139" smd circle
			(at 9.525 -1.905 90)
			(size 0.635 0.635)
			(layers "B.Cu" "B.Mask" "B.Paste")
			(net "CPLD_NIC_MEZZ_ID1")
		)
		(pad "140" smd circle
			(at 9.525 -0.635 90)
			(size 0.635 0.635)
			(layers "B.Cu" "B.Mask" "B.Paste")
			(net "GND")
		)
		(pad "141" smd circle
			(at 9.525 0.635 90)
			(size 0.635 0.635)
			(layers "B.Cu" "B.Mask" "B.Paste")
			(net "NFP_SERDES0_RX0_P")
		)
		(pad "142" smd circle
			(at 9.525 1.905 90)
			(size 0.635 0.635)
			(layers "B.Cu" "B.Mask" "B.Paste")
			(net "GND")
		)
		(pad "143" smd circle
			(at 9.525 3.175 90)
			(size 0.635 0.635)
			(layers "B.Cu" "B.Mask" "B.Paste")
			(net "NFP_SERDES1_RX3_N")
		)
		(pad "144" smd circle
			(at 9.525 4.445 90)
			(size 0.635 0.635)
			(layers "B.Cu" "B.Mask" "B.Paste")
			(net "GND")
		)
		(pad "145" smd circle
			(at 10.795 -4.445 90)
			(size 0.635 0.635)
			(layers "B.Cu" "B.Mask" "B.Paste")
			(net "EXT_12.0V")
		)
		(pad "146" smd circle
			(at 10.795 -3.175 90)
			(size 0.635 0.635)
			(layers "B.Cu" "B.Mask" "B.Paste")
			(net "EXT_3.3V")
		)
		(pad "147" smd circle
			(at 10.795 -1.905 90)
			(size 0.635 0.635)
			(layers "B.Cu" "B.Mask" "B.Paste")
			(net "MAIN_3.3V")
		)
		(pad "148" smd circle
			(at 10.795 -0.635 90)
			(size 0.635 0.635)
			(layers "B.Cu" "B.Mask" "B.Paste")
			(net "GND")
		)
		(pad "149" smd circle
			(at 10.795 0.635 90)
			(size 0.635 0.635)
			(layers "B.Cu" "B.Mask" "B.Paste")
			(net "NFP_SERDES0_RX0_N")
		)
		(pad "150" smd circle
			(at 10.795 1.905 90)
			(size 0.635 0.635)
			(layers "B.Cu" "B.Mask" "B.Paste")
			(net "GND")
		)
		(pad "151" smd circle
			(at 10.795 3.175 90)
			(size 0.635 0.635)
			(layers "B.Cu" "B.Mask" "B.Paste")
			(net "NFP_SERDES1_RX3_P")
		)
		(pad "152" smd circle
			(at 10.795 4.445 90)
			(size 0.635 0.635)
			(layers "B.Cu" "B.Mask" "B.Paste")
			(net "NWK0_I2C_SDA")
		)
		(pad "153" smd circle
			(at 12.065 -4.445 90)
			(size 0.635 0.635)
			(layers "B.Cu" "B.Mask" "B.Paste")
			(net "EXT_12.0V")
		)
		(pad "154" smd circle
			(at 12.065 -3.175 90)
			(size 0.635 0.635)
			(layers "B.Cu" "B.Mask" "B.Paste")
			(net "EXT_3.3V")
		)
		(pad "155" smd circle
			(at 12.065 -1.905 90)
			(size 0.635 0.635)
			(layers "B.Cu" "B.Mask" "B.Paste")
			(net "MAIN_3.3V")
		)
		(pad "156" smd circle
			(at 12.065 -0.635 90)
			(size 0.635 0.635)
			(layers "B.Cu" "B.Mask" "B.Paste")
			(net "MAIN_3.3V")
		)
		(pad "157" smd circle
			(at 12.065 0.635 90)
			(size 0.635 0.635)
			(layers "B.Cu" "B.Mask" "B.Paste")
			(net "GND")
		)
		(pad "158" smd circle
			(at 12.065 1.905 90)
			(size 0.635 0.635)
			(layers "B.Cu" "B.Mask" "B.Paste")
			(net "NWK0_MOD_PRES_L")
		)
		(pad "159" smd circle
			(at 12.065 3.175 90)
			(size 0.635 0.635)
			(layers "B.Cu" "B.Mask" "B.Paste")
			(net "GND")
		)
		(pad "160" smd circle
			(at 12.065 4.445 90)
			(size 0.635 0.635)
			(layers "B.Cu" "B.Mask" "B.Paste")
			(net "NWK0_I2C_SCL")
		)
	)
)
